FILE_TYPE = MACRO_DRAWING;
SET COLOR_WIRE YELLOW;
SET COLOR_PROP ORANGE;
SET COLOR_DOT WHITE;
SET COLOR_ARC YELLOW;
SET COLOR_BODY GREEN;
SET COLOR_NOTE PURPLE;
SET PROP_DISPLAY VALUE;
SET PAGE_NUMBER P365;
FORCEADD OFFPAGE..1
(9050 3125);
FORCEPROP 2 LAST $XR0 263 
J 0
(8768 3125);
DISPLAY 0.638298 (8768 3125);
PAINT MONO (8768 3125);
FORCEPROP 2 LAST $XR1 268 
J 0
(8648 3125);
DISPLAY 0.638298 (8648 3125);
PAINT MONO (8648 3125);
FORCEPROP 2 LAST $XR2 189 
J 0
(8528 3125);
DISPLAY 0.638298 (8528 3125);
PAINT MONO (8528 3125);
FORCEPROP 2 LAST $XR3 254 
J 0
(8408 3125);
DISPLAY 0.638298 (8408 3125);
PAINT MONO (8408 3125);
FORCEPROP 2 LAST CDS_LIB standard
J 0
(9050 3125);
DISPLAY INVISIBLE (9050 3125);
FORCEPROP 1 LAST OFFPAGE TRUE
J 0
(9375 3000);
DISPLAY 0.872340 (9375 3000);
PAINT GREEN (9375 3000);
DISPLAY INVISIBLE (9375 3000);
FORCEPROP 1 LAST COMMENT_BODY TRUE
J 0
(9175 3025);
DISPLAY 0.872340 (9175 3025);
PAINT GREEN (9175 3025);
DISPLAY INVISIBLE (9175 3025);
FORCEPROP 2 LAST PATH I1
J 0
(8800 3175);
DISPLAY 1.021277 (8800 3175);
DISPLAY INVISIBLE (8800 3175);
FORCEADD Q_RES..2
(14600 4050);
FORCEPROP 1 LAST LOCATION R2530
J 0
(14645 4175);
DISPLAY 0.978723 (14645 4175);
FORCEPROP 0 LAST $SEC 1
J 0
(14650 4225);
DISPLAY 0.680851 (14650 4225);
PAINT MONO (14650 4225);
DISPLAY INVISIBLE (14650 4225);
FORCEPROP 0 LAST CDS_SEC 1
J 0
(14650 4225);
DISPLAY 1.021277 (14650 4225);
DISPLAY INVISIBLE (14650 4225);
FORCEPROP 1 LASTPIN (14600 4150) $PN 1
J 0
(14605 4112);
DISPLAY 0.787234 (14605 4112);
PAINT MONO (14605 4112);
FORCEPROP 1 LASTPIN (14600 3950) $PN 2
J 0
(14605 3960);
DISPLAY 0.787234 (14605 3960);
PAINT MONO (14605 3960);
FORCEPROP 1 LAST WATTAGE 1/16W
J 0
(14640 4025);
DISPLAY 0.510638 (14640 4025);
FORCEPROP 1 LAST MATERIAL CHIP
J 0
(14640 3975);
DISPLAY 0.510638 (14640 3975);
FORCEPROP 1 LAST PACK_TYPE 0402LF
J 0
(14640 3875);
DISPLAY 0.510638 (14640 3875);
FORCEPROP 1 LAST TOLERANCE 5%
J 0
(14645 4075);
DISPLAY 0.510638 (14645 4075);
FORCEPROP 1 LAST VALUE 4.7K
J 0
(14645 4125);
DISPLAY 0.510638 (14645 4125);
FORCEPROP 2 LAST CDS_LIB pure_quanta
J 0
(14600 4050);
DISPLAY INVISIBLE (14600 4050);
FORCEPROP 1 LAST PATH I10
J 0
(14650 4225);
DISPLAY 0.978723 (14650 4225);
PAINT WHITE (14650 4225);
DISPLAY INVISIBLE (14650 4225);
FORCEPROP 1 LAST PART_NUMBER CS24702JB10
J 0
(14640 3925);
DISPLAY 0.510638 (14640 3925);
DISPLAY INVISIBLE (14640 3925);
FORCEADD UNIVERSAL_POWER..1
(14600 4300);
FORCEPROP 3 LASTPIN (14600 4250) SIG_NAME P12V_AUX\g
J 0
(14610 4260);
DISPLAY 0.659574 (14610 4260);
PAINT MONO (14610 4260);
DISPLAY INVISIBLE (14610 4260);
FORCEPROP 1 LAST HDL_POWER P12V_AUX
J 1
(14600 4350);
DISPLAY 0.872340 (14600 4350);
PAINT GREEN (14600 4350);
FORCEPROP 2 LAST CDS_LIB pure_quanta_power
J 0
(14600 4300);
DISPLAY INVISIBLE (14600 4300);
FORCEPROP 1 LAST PATH I11
J 0
(14650 4325);
DISPLAY 0.872340 (14650 4325);
PAINT AQUA (14650 4325);
DISPLAY INVISIBLE (14650 4325);
FORCEADD MOSFET_NCH_GDS_ESD_PROTECTED..1
(14000 3450);
FORCEPROP 1 LAST LOCATION Q54
J 0
(14142 3414);
DISPLAY 0.723404 (14142 3414);
PAINT GREEN (14142 3414);
FORCEPROP 0 LAST $SEC 1
J 0
(14150 3600);
DISPLAY 0.680851 (14150 3600);
PAINT MONO (14150 3600);
DISPLAY INVISIBLE (14150 3600);
FORCEPROP 0 LAST CDS_SEC 1
J 0
(14150 3600);
DISPLAY 1.021277 (14150 3600);
DISPLAY INVISIBLE (14150 3600);
FORCEPROP 0 LASTPIN (14025 3650) $PN D
R 1
J 0
(14015 3660);
DISPLAY 0.680851 (14015 3660);
PAINT MONO (14015 3660);
FORCEPROP 0 LASTPIN (13825 3450) $PN G
J 2
(13815 3460);
DISPLAY 0.680851 (13815 3460);
PAINT MONO (13815 3460);
FORCEPROP 0 LASTPIN (14025 3250) $PN S
R 1
J 2
(14015 3240);
DISPLAY 0.680851 (14015 3240);
PAINT MONO (14015 3240);
FORCEPROP 2 LAST PART_TYPE SMLF
J 0
(14150 3550);
DISPLAY 0.680851 (14150 3550);
FORCEPROP 2 LAST VALUE 2N7002K
J 0
(14150 3500);
DISPLAY 0.680851 (14150 3500);
FORCEPROP 1 LAST MATERIAL IC
J 0
(14142 3305);
DISPLAY 0.723404 (14142 3305);
PAINT GREEN (14142 3305);
FORCEPROP 1 LAST NEEDS_NO_SIZE TRUE
J 0
(14125 3340);
DISPLAY 0.723404 (14125 3340);
PAINT GREEN (14125 3340);
DISPLAY INVISIBLE (14125 3340);
FORCEPROP 1 LAST CDS_LMAN_SYM_OUTLINE -125,150,125,-150
J 0
(14000 3450);
DISPLAY 0.468085 (14000 3450);
PAINT GREEN (14000 3450);
DISPLAY INVISIBLE (14000 3450);
FORCEPROP 2 LAST CDS_LIB pure_quanta
J 2
(14000 3450);
DISPLAY INVISIBLE (14000 3450);
FORCEPROP 1 LAST PATH I14
J 0
(14125 3300);
DISPLAY 0.723404 (14125 3300);
PAINT GREEN (14125 3300);
DISPLAY INVISIBLE (14125 3300);
FORCEPROP 1 LAST PART_NUMBER BAM70020002
J 0
(14142 3362);
DISPLAY 0.723404 (14142 3362);
PAINT GREEN (14142 3362);
DISPLAY INVISIBLE (14142 3362);
FORCEADD UNIVERSAL_GND..1
(14025 3050);
FORCEPROP 3 LASTPIN (14025 3100) SIG_NAME GND\g
J 0
(14035 3110);
DISPLAY 0.659574 (14035 3110);
PAINT MONO (14035 3110);
DISPLAY INVISIBLE (14035 3110);
FORCEPROP 2 LAST CDS_LIB pure_quanta_power
J 0
(14025 3050);
DISPLAY INVISIBLE (14025 3050);
FORCEPROP 1 LAST HDL_POWER GND
J 1
(14050 2975);
DISPLAY 0.872340 (14050 2975);
PAINT GREEN (14050 2975);
DISPLAY INVISIBLE (14050 2975);
FORCEPROP 1 LAST PATH I15
J 0
(14100 3050);
DISPLAY 0.872340 (14100 3050);
PAINT AQUA (14100 3050);
DISPLAY INVISIBLE (14100 3050);
FORCEADD 74LVC2G07DW7..1
(11550 1350);
FORCEPROP 1 LAST LOCATION U8004
J 0
(11381 1731);
DISPLAY 0.723404 (11381 1731);
PAINT GREEN (11381 1731);
FORCEPROP 2 LAST SEC 1
J 0
(11400 1875);
DISPLAY 0.680851 (11400 1875);
PAINT MONO (11400 1875);
DISPLAY INVISIBLE (11400 1875);
FORCEPROP 2 LASTPIN (11225 1400) $PN 1
J 2
(11215 1410);
DISPLAY 0.680851 (11215 1410);
PAINT MONO (11215 1410);
FORCEPROP 2 LASTPIN (11875 1400) $PN 6
J 0
(11885 1410);
DISPLAY 0.680851 (11885 1410);
PAINT MONO (11885 1410);
FORCEPROP 2 LASTPIN (11225 1300) $PN 3
J 2
(11215 1310);
DISPLAY 0.680851 (11215 1310);
PAINT MONO (11215 1310);
FORCEPROP 2 LASTPIN (11875 1300) $PN 4
J 0
(11885 1310);
DISPLAY 0.680851 (11885 1310);
PAINT MONO (11885 1310);
FORCEPROP 2 LASTPIN (11225 1350) $PN 2
J 2
(11215 1360);
DISPLAY 0.680851 (11215 1360);
PAINT MONO (11215 1360);
FORCEPROP 2 LASTPIN (11875 1350) $PN 5
J 0
(11885 1360);
DISPLAY 0.680851 (11885 1360);
PAINT MONO (11885 1360);
FORCEPROP 2 LAST VALUE 74LVC2G07DW-7
J 0
(11400 1775);
DISPLAY 0.680851 (11400 1775);
FORCEPROP 1 LAST MATERIAL EMPTY
J 0
(11381 1457);
DISPLAY 0.723404 (11381 1457);
PAINT GREEN (11381 1457);
FORCEPROP 2 LAST PART_TYPE SMLF
J 0
(11400 1825);
DISPLAY 0.680851 (11400 1825);
FORCEPROP 2 LAST SEC_TYPE 
J 0
(11400 1875);
DISPLAY 0.680851 (11400 1875);
DISPLAY INVISIBLE (11400 1875);
FORCEPROP 2 LAST CDS_LIB pure_quanta
J 0
(11550 1350);
DISPLAY INVISIBLE (11550 1350);
FORCEPROP 1 LAST NEEDS_NO_SIZE TRUE
J 0
(11550 1350);
DISPLAY 0.723404 (11550 1350);
PAINT GREEN (11550 1350);
DISPLAY INVISIBLE (11550 1350);
FORCEPROP 1 LAST CDS_LMAN_SYM_OUTLINE -175,100,175,-100
J 0
(11550 1350);
DISPLAY 0.468085 (11550 1350);
PAINT GREEN (11550 1350);
DISPLAY INVISIBLE (11550 1350);
FORCEPROP 1 LAST PATH I16
J 0
(11550 1350);
DISPLAY 0.723404 (11550 1350);
PAINT GREEN (11550 1350);
DISPLAY INVISIBLE (11550 1350);
FORCEPROP 1 LAST PART_NUMBER AL002G07003
J 0
(11381 1584);
DISPLAY 0.723404 (11381 1584);
PAINT GREEN (11381 1584);
DISPLAY INVISIBLE (11381 1584);
FORCEADD UNIVERSAL_GND..1
(11150 1200);
FORCEPROP 3 LASTPIN (11150 1250) SIG_NAME GND\g
J 0
(11160 1260);
DISPLAY 0.659574 (11160 1260);
PAINT MONO (11160 1260);
DISPLAY INVISIBLE (11160 1260);
FORCEPROP 2 LAST CDS_LIB pure_quanta_power
J 0
(11150 1200);
DISPLAY INVISIBLE (11150 1200);
FORCEPROP 1 LAST HDL_POWER GND
J 1
(11175 1125);
DISPLAY 0.872340 (11175 1125);
PAINT GREEN (11175 1125);
DISPLAY INVISIBLE (11175 1125);
FORCEPROP 1 LAST PATH I17
J 0
(11225 1200);
DISPLAY 0.872340 (11225 1200);
PAINT AQUA (11225 1200);
DISPLAY INVISIBLE (11225 1200);
FORCEADD Q_RES..1
(9975 1400);
FORCEPROP 1 LAST LOCATION R8104
J 0
(9925 1450);
DISPLAY 0.978723 (9925 1450);
FORCEPROP 0 LAST $SEC 1
J 0
(9925 1550);
DISPLAY 0.680851 (9925 1550);
PAINT MONO (9925 1550);
DISPLAY INVISIBLE (9925 1550);
FORCEPROP 0 LAST CDS_SEC 1
J 0
(9925 1550);
DISPLAY 0.680851 (9925 1550);
DISPLAY INVISIBLE (9925 1550);
FORCEPROP 1 LASTPIN (9875 1400) $PN 1
J 0
(9887 1412);
DISPLAY 0.787234 (9887 1412);
PAINT MONO (9887 1412);
FORCEPROP 1 LASTPIN (10075 1400) $PN 2
J 0
(10037 1412);
DISPLAY 0.787234 (10037 1412);
PAINT MONO (10037 1412);
FORCEPROP 1 LAST PACK_TYPE 0402LF
J 0
(10225 1250);
DISPLAY 0.978723 (10225 1250);
FORCEPROP 1 LAST TOLERANCE 5%
J 0
(9975 1300);
DISPLAY 0.978723 (9975 1300);
FORCEPROP 1 LAST MATERIAL EMPTY
J 0
(9975 1250);
DISPLAY 0.978723 (9975 1250);
FORCEPROP 1 LAST VALUE 0
J 2
(9950 1300);
DISPLAY 0.978723 (9950 1300);
FORCEPROP 1 LAST WATTAGE 1/16W
J 2
(9950 1250);
DISPLAY 0.978723 (9950 1250);
FORCEPROP 2 LAST CDS_LIB pure_quanta
J 0
(9975 1400);
DISPLAY INVISIBLE (9975 1400);
FORCEPROP 1 LAST PATH I18
J 0
(9925 1550);
DISPLAY 0.978723 (9925 1550);
PAINT WHITE (9925 1550);
DISPLAY INVISIBLE (9925 1550);
FORCEPROP 1 LAST PART_NUMBER CS00002JB13
J 0
(9925 1500);
DISPLAY 0.978723 (9925 1500);
DISPLAY INVISIBLE (9925 1500);
FORCEADD OFFPAGE..1
(8375 1400);
FORCEPROP 2 LAST $XR0 150 
J 0
(8093 1400);
DISPLAY 0.638298 (8093 1400);
PAINT MONO (8093 1400);
FORCEPROP 2 LAST $XR1 241 
J 0
(7973 1400);
DISPLAY 0.638298 (7973 1400);
PAINT MONO (7973 1400);
FORCEPROP 2 LAST CDS_LIB standard
J 0
(8375 1400);
DISPLAY INVISIBLE (8375 1400);
FORCEPROP 1 LAST OFFPAGE TRUE
J 0
(8700 1275);
DISPLAY 0.872340 (8700 1275);
PAINT GREEN (8700 1275);
DISPLAY INVISIBLE (8700 1275);
FORCEPROP 1 LAST COMMENT_BODY TRUE
J 0
(8500 1300);
DISPLAY 0.872340 (8500 1300);
PAINT GREEN (8500 1300);
DISPLAY INVISIBLE (8500 1300);
FORCEPROP 2 LAST PATH I19
J 0
(8425 1475);
DISPLAY 0.680851 (8425 1475);
DISPLAY INVISIBLE (8425 1475);
FORCEADD Q_RES..1
(13875 1400);
FORCEPROP 1 LAST LOCATION R8105
J 0
(13825 1450);
DISPLAY 0.978723 (13825 1450);
FORCEPROP 0 LAST $SEC 1
J 0
(13825 1550);
DISPLAY 0.680851 (13825 1550);
PAINT MONO (13825 1550);
DISPLAY INVISIBLE (13825 1550);
FORCEPROP 0 LAST CDS_SEC 1
J 0
(13825 1550);
DISPLAY 0.680851 (13825 1550);
DISPLAY INVISIBLE (13825 1550);
FORCEPROP 1 LASTPIN (13775 1400) $PN 1
J 0
(13787 1412);
DISPLAY 0.787234 (13787 1412);
PAINT MONO (13787 1412);
FORCEPROP 1 LASTPIN (13975 1400) $PN 2
J 0
(13937 1412);
DISPLAY 0.787234 (13937 1412);
PAINT MONO (13937 1412);
FORCEPROP 1 LAST VALUE 0
J 2
(13850 1300);
DISPLAY 0.978723 (13850 1300);
FORCEPROP 1 LAST TOLERANCE 5%
J 0
(13875 1300);
DISPLAY 0.978723 (13875 1300);
FORCEPROP 1 LAST WATTAGE 1/16W
J 2
(13850 1250);
DISPLAY 0.978723 (13850 1250);
FORCEPROP 1 LAST MATERIAL EMPTY
J 0
(13875 1250);
DISPLAY 0.978723 (13875 1250);
FORCEPROP 1 LAST PACK_TYPE 0402LF
J 0
(14125 1250);
DISPLAY 0.978723 (14125 1250);
FORCEPROP 2 LAST CDS_LIB pure_quanta
J 0
(13875 1400);
DISPLAY INVISIBLE (13875 1400);
FORCEPROP 1 LAST PATH I20
J 0
(13825 1550);
DISPLAY 0.978723 (13825 1550);
PAINT WHITE (13825 1550);
DISPLAY INVISIBLE (13825 1550);
FORCEPROP 1 LAST PART_NUMBER CS00002JB13
J 0
(13825 1500);
DISPLAY 0.978723 (13825 1500);
DISPLAY INVISIBLE (13825 1500);
FORCEADD OFFPAGE..2
(16050 1400);
FORCEPROP 2 LAST $XR0 81 
J 0
(16239 1400);
DISPLAY 0.638298 (16239 1400);
PAINT MONO (16239 1400);
FORCEPROP 2 LAST CDS_LIB standard
J 0
(16050 1400);
DISPLAY INVISIBLE (16050 1400);
FORCEPROP 1 LAST OFFPAGE TRUE
J 0
(16375 1275);
DISPLAY 0.872340 (16375 1275);
PAINT AQUA (16375 1275);
DISPLAY INVISIBLE (16375 1275);
FORCEPROP 1 LAST COMMENT_BODY TRUE
J 0
(16005 1305);
DISPLAY 0.872340 (16005 1305);
PAINT GREEN (16005 1305);
DISPLAY INVISIBLE (16005 1305);
FORCEPROP 2 LAST PATH I21
J 0
(16225 1475);
DISPLAY 0.680851 (16225 1475);
DISPLAY INVISIBLE (16225 1475);
FORCEADD UNIVERSAL_POWER..1
(12200 2375);
FORCEPROP 3 LASTPIN (12200 2325) SIG_NAME P3V3_AUX\g
J 0
(12210 2335);
DISPLAY 0.659574 (12210 2335);
PAINT MONO (12210 2335);
DISPLAY INVISIBLE (12210 2335);
FORCEPROP 1 LAST HDL_POWER P3V3_AUX
J 1
(12200 2425);
DISPLAY 0.872340 (12200 2425);
PAINT GREEN (12200 2425);
FORCEPROP 2 LAST CDS_LIB pure_quanta_power
J 0
(12200 2375);
DISPLAY INVISIBLE (12200 2375);
FORCEPROP 1 LAST PATH I22
J 0
(12250 2400);
DISPLAY 0.872340 (12250 2400);
PAINT AQUA (12250 2400);
DISPLAY INVISIBLE (12250 2400);
FORCEADD Q_CAP..1
(12400 2050);
FORCEPROP 1 LAST LOCATION C8013
J 0
(12450 2150);
DISPLAY 0.978723 (12450 2150);
FORCEPROP 0 LAST $SEC 1
J 0
(12450 2200);
DISPLAY 0.680851 (12450 2200);
PAINT MONO (12450 2200);
DISPLAY INVISIBLE (12450 2200);
FORCEPROP 0 LAST CDS_SEC 1
J 0
(12450 2200);
DISPLAY 0.680851 (12450 2200);
DISPLAY INVISIBLE (12450 2200);
FORCEPROP 1 LASTPIN (12400 2150) $PN 1
J 0
(12410 2130);
DISPLAY 0.787234 (12410 2130);
PAINT MONO (12410 2130);
FORCEPROP 1 LASTPIN (12400 1950) $PN 2
J 0
(12410 1930);
DISPLAY 0.787234 (12410 1930);
PAINT MONO (12410 1930);
FORCEPROP 1 LAST VOLTAGE 25V
J 0
(12450 2050);
DISPLAY 0.978723 (12450 2050);
FORCEPROP 1 LAST PACK_TYPE 0402
J 0
(12450 1850);
DISPLAY 0.978723 (12450 1850);
FORCEPROP 1 LAST MATERIAL EMPTY
J 0
(12450 1950);
DISPLAY 0.978723 (12450 1950);
FORCEPROP 1 LAST TOLERANCE 10%
J 0
(12450 2000);
DISPLAY 0.978723 (12450 2000);
FORCEPROP 1 LAST VALUE 0.1UF
J 0
(12450 2100);
DISPLAY 0.978723 (12450 2100);
FORCEPROP 2 LAST CDS_LIB pure_quanta
J 0
(12400 2050);
DISPLAY INVISIBLE (12400 2050);
FORCEPROP 1 LAST PATH I23
J 0
(12450 2200);
DISPLAY 0.978723 (12450 2200);
PAINT WHITE (12450 2200);
DISPLAY INVISIBLE (12450 2200);
FORCEPROP 1 LAST PART_NUMBER CH4104K1B00
J 0
(12450 1900);
DISPLAY 0.978723 (12450 1900);
DISPLAY INVISIBLE (12450 1900);
FORCEADD UNIVERSAL_GND..1
(12400 1750);
FORCEPROP 3 LASTPIN (12400 1800) SIG_NAME GND\g
J 0
(12410 1810);
DISPLAY 0.659574 (12410 1810);
PAINT MONO (12410 1810);
DISPLAY INVISIBLE (12410 1810);
FORCEPROP 2 LAST CDS_LIB pure_quanta_power
J 0
(12400 1750);
DISPLAY INVISIBLE (12400 1750);
FORCEPROP 1 LAST HDL_POWER GND
J 1
(12425 1675);
DISPLAY 0.872340 (12425 1675);
PAINT GREEN (12425 1675);
DISPLAY INVISIBLE (12425 1675);
FORCEPROP 1 LAST PATH I24
J 0
(12475 1750);
DISPLAY 0.872340 (12475 1750);
PAINT AQUA (12475 1750);
DISPLAY INVISIBLE (12475 1750);
FORCEADD Q_CAP..1
(9450 900);
FORCEPROP 1 LAST LOCATION C8012
J 0
(9500 1000);
DISPLAY 0.978723 (9500 1000);
FORCEPROP 0 LAST $SEC 1
J 0
(9500 1050);
DISPLAY 0.680851 (9500 1050);
PAINT MONO (9500 1050);
DISPLAY INVISIBLE (9500 1050);
FORCEPROP 0 LAST CDS_SEC 1
J 0
(9500 1050);
DISPLAY 0.680851 (9500 1050);
DISPLAY INVISIBLE (9500 1050);
FORCEPROP 1 LASTPIN (9450 1000) $PN 1
J 0
(9460 980);
DISPLAY 0.787234 (9460 980);
PAINT MONO (9460 980);
FORCEPROP 1 LASTPIN (9450 800) $PN 2
J 0
(9460 780);
DISPLAY 0.787234 (9460 780);
PAINT MONO (9460 780);
FORCEPROP 1 LAST VALUE 1UF
J 0
(9500 950);
DISPLAY 0.978723 (9500 950);
FORCEPROP 1 LAST PACK_TYPE C0402
J 0
(9500 700);
DISPLAY 0.978723 (9500 700);
FORCEPROP 1 LAST MATERIAL EMPTY
J 0
(9500 800);
DISPLAY 0.978723 (9500 800);
FORCEPROP 1 LAST TOLERANCE 10%
J 0
(9500 850);
DISPLAY 0.978723 (9500 850);
FORCEPROP 1 LAST VOLTAGE 25V
J 0
(9500 900);
DISPLAY 0.978723 (9500 900);
FORCEPROP 2 LAST CDS_LIB pure_quanta
J 0
(9450 900);
DISPLAY INVISIBLE (9450 900);
FORCEPROP 1 LAST PATH I25
J 0
(9500 1050);
DISPLAY 0.978723 (9500 1050);
PAINT WHITE (9500 1050);
DISPLAY INVISIBLE (9500 1050);
FORCEPROP 1 LAST PART_NUMBER CH5104KEB02
J 0
(9500 750);
DISPLAY 0.978723 (9500 750);
DISPLAY INVISIBLE (9500 750);
FORCEADD UNIVERSAL_GND..1
(9450 450);
FORCEPROP 3 LASTPIN (9450 500) SIG_NAME GND\g
J 0
(9460 510);
DISPLAY 0.659574 (9460 510);
PAINT MONO (9460 510);
DISPLAY INVISIBLE (9460 510);
FORCEPROP 2 LAST CDS_LIB pure_quanta_power
J 0
(9450 450);
DISPLAY INVISIBLE (9450 450);
FORCEPROP 1 LAST HDL_POWER GND
J 1
(9475 375);
DISPLAY 0.872340 (9475 375);
PAINT GREEN (9475 375);
DISPLAY INVISIBLE (9475 375);
FORCEPROP 1 LAST PATH I26
J 0
(9525 450);
DISPLAY 0.872340 (9525 450);
PAINT AQUA (9525 450);
DISPLAY INVISIBLE (9525 450);
FORCEADD Q_RES..2
(9375 1900);
FORCEPROP 1 LAST LOCATION R8103
J 0
(9420 2025);
DISPLAY 0.978723 (9420 2025);
FORCEPROP 0 LAST $SEC 1
J 0
(9425 2075);
DISPLAY 0.680851 (9425 2075);
PAINT MONO (9425 2075);
DISPLAY INVISIBLE (9425 2075);
FORCEPROP 0 LAST CDS_SEC 1
J 0
(9425 2075);
DISPLAY 0.680851 (9425 2075);
DISPLAY INVISIBLE (9425 2075);
FORCEPROP 1 LASTPIN (9375 2000) $PN 1
J 0
(9380 1962);
DISPLAY 0.787234 (9380 1962);
PAINT MONO (9380 1962);
FORCEPROP 1 LASTPIN (9375 1800) $PN 2
J 0
(9380 1810);
DISPLAY 0.787234 (9380 1810);
PAINT MONO (9380 1810);
FORCEPROP 1 LAST WATTAGE 1/16W
J 0
(9415 1875);
DISPLAY 0.978723 (9415 1875);
FORCEPROP 1 LAST PACK_TYPE 0402LF
J 0
(9415 1725);
DISPLAY 0.978723 (9415 1725);
FORCEPROP 1 LAST MATERIAL EMPTY
J 0
(9415 1825);
DISPLAY 0.978723 (9415 1825);
FORCEPROP 1 LAST TOLERANCE 1%
J 0
(9420 1925);
DISPLAY 0.978723 (9420 1925);
FORCEPROP 1 LAST VALUE 8.45K
J 0
(9420 1975);
DISPLAY 0.978723 (9420 1975);
FORCEPROP 2 LAST CDS_LIB pure_quanta
J 0
(9375 1900);
DISPLAY INVISIBLE (9375 1900);
FORCEPROP 1 LAST PATH I27
J 0
(9425 2075);
DISPLAY 0.978723 (9425 2075);
PAINT WHITE (9425 2075);
DISPLAY INVISIBLE (9425 2075);
FORCEPROP 1 LAST PART_NUMBER CS28452FB06
J 0
(9415 1775);
DISPLAY 0.978723 (9415 1775);
DISPLAY INVISIBLE (9415 1775);
FORCEADD UNIVERSAL_POWER..1
(9375 2300);
FORCEPROP 3 LASTPIN (9375 2250) SIG_NAME P3V3_AUX\g
J 0
(9385 2260);
DISPLAY 0.659574 (9385 2260);
PAINT MONO (9385 2260);
DISPLAY INVISIBLE (9385 2260);
FORCEPROP 1 LAST HDL_POWER P3V3_AUX
J 1
(9375 2350);
DISPLAY 0.872340 (9375 2350);
PAINT GREEN (9375 2350);
FORCEPROP 2 LAST CDS_LIB pure_quanta_power
J 0
(9375 2300);
DISPLAY INVISIBLE (9375 2300);
FORCEPROP 1 LAST PATH I28
J 0
(9425 2325);
DISPLAY 0.872340 (9425 2325);
PAINT AQUA (9425 2325);
DISPLAY INVISIBLE (9425 2325);
FORCEADD Q_RES..1
(10325 3125);
FORCEPROP 1 LAST LOCATION R2531
J 0
(10075 3125);
DISPLAY 0.787234 (10075 3125);
FORCEPROP 0 LAST $SEC 1
J 0
(10625 3200);
DISPLAY 0.680851 (10625 3200);
PAINT MONO (10625 3200);
DISPLAY INVISIBLE (10625 3200);
FORCEPROP 0 LAST CDS_SEC 1
J 0
(10625 3200);
DISPLAY 1.021277 (10625 3200);
DISPLAY INVISIBLE (10625 3200);
FORCEPROP 1 LASTPIN (10225 3125) $PN 1
J 0
(10237 3137);
DISPLAY 0.787234 (10237 3137);
PAINT MONO (10237 3137);
FORCEPROP 1 LASTPIN (10425 3125) $PN 2
J 0
(10387 3137);
DISPLAY 0.787234 (10387 3137);
PAINT MONO (10387 3137);
FORCEPROP 1 LAST VALUE 0
J 2
(10475 3125);
DISPLAY 0.404255 (10475 3125);
FORCEPROP 1 LAST MATERIAL CHIP
J 0
(10575 3125);
DISPLAY 0.404255 (10575 3125);
FORCEPROP 1 LAST TOLERANCE 5%
J 0
(10500 3125);
DISPLAY 0.404255 (10500 3125);
FORCEPROP 1 LAST WATTAGE 1/16W
J 2
(10625 3175);
DISPLAY 0.319149 (10625 3175);
FORCEPROP 1 LAST PACK_TYPE 0402LF
J 0
(10450 3175);
DISPLAY 0.319149 (10450 3175);
FORCEPROP 2 LAST CDS_LIB pure_quanta
J 0
(10325 3125);
DISPLAY INVISIBLE (10325 3125);
FORCEPROP 1 LAST PATH I3
J 0
(10275 3275);
DISPLAY 0.978723 (10275 3275);
PAINT WHITE (10275 3275);
DISPLAY INVISIBLE (10275 3275);
FORCEPROP 1 LAST PART_NUMBER CS00002JB13
J 0
(10450 3150);
DISPLAY 0.319149 (10450 3150);
DISPLAY INVISIBLE (10450 3150);
FORCEADD UNIVERSAL_POWER..1
(14500 2400);
FORCEPROP 3 LASTPIN (14500 2350) SIG_NAME P3V3_AUX\g
J 0
(14510 2360);
DISPLAY 0.659574 (14510 2360);
PAINT MONO (14510 2360);
DISPLAY INVISIBLE (14510 2360);
FORCEPROP 1 LAST HDL_POWER P3V3_AUX
J 1
(14500 2450);
DISPLAY 0.872340 (14500 2450);
PAINT GREEN (14500 2450);
FORCEPROP 2 LAST CDS_LIB pure_quanta_power
J 0
(14500 2400);
DISPLAY INVISIBLE (14500 2400);
FORCEPROP 1 LAST PATH I30
J 0
(14550 2425);
DISPLAY 0.872340 (14550 2425);
PAINT AQUA (14550 2425);
DISPLAY INVISIBLE (14550 2425);
FORCEADD Q_RES..2
(14500 2050);
FORCEPROP 1 LAST LOCATION R8106
J 0
(14545 2175);
DISPLAY 0.978723 (14545 2175);
FORCEPROP 0 LAST $SEC 1
J 0
(14550 2225);
DISPLAY 0.680851 (14550 2225);
PAINT MONO (14550 2225);
DISPLAY INVISIBLE (14550 2225);
FORCEPROP 0 LAST CDS_SEC 1
J 0
(14550 2225);
DISPLAY 0.680851 (14550 2225);
DISPLAY INVISIBLE (14550 2225);
FORCEPROP 1 LASTPIN (14500 2150) $PN 1
J 0
(14505 2112);
DISPLAY 0.787234 (14505 2112);
PAINT MONO (14505 2112);
FORCEPROP 1 LASTPIN (14500 1950) $PN 2
J 0
(14505 1960);
DISPLAY 0.787234 (14505 1960);
PAINT MONO (14505 1960);
FORCEPROP 1 LAST VALUE 1K
J 0
(14545 2125);
DISPLAY 0.723404 (14545 2125);
FORCEPROP 1 LAST TOLERANCE 1%
J 0
(14545 2075);
DISPLAY 0.723404 (14545 2075);
FORCEPROP 1 LAST WATTAGE 1/16W
J 0
(14540 2025);
DISPLAY 0.723404 (14540 2025);
FORCEPROP 1 LAST PACK_TYPE 0402LF
J 0
(14550 1925);
DISPLAY 0.723404 (14550 1925);
FORCEPROP 1 LAST MATERIAL CHIP
J 0
(14540 1975);
DISPLAY 0.723404 (14540 1975);
FORCEPROP 2 LAST CDS_LIB pure_quanta
J 0
(14500 2050);
DISPLAY INVISIBLE (14500 2050);
FORCEPROP 1 LAST PATH I31
J 0
(14550 2225);
DISPLAY 0.978723 (14550 2225);
PAINT WHITE (14550 2225);
DISPLAY INVISIBLE (14550 2225);
FORCEPROP 1 LAST PART_NUMBER CS21002FB06
J 0
(14540 1925);
DISPLAY 0.723404 (14540 1925);
PAINT WHITE (14540 1925);
DISPLAY INVISIBLE (14540 1925);
FORCEADD UNIVERSAL_GND..1
(11650 2775);
FORCEPROP 3 LASTPIN (11650 2825) SIG_NAME GND\g
J 0
(11660 2835);
DISPLAY 0.659574 (11660 2835);
PAINT MONO (11660 2835);
DISPLAY INVISIBLE (11660 2835);
FORCEPROP 2 LAST CDS_LIB pure_quanta_power
J 0
(11650 2775);
DISPLAY INVISIBLE (11650 2775);
FORCEPROP 1 LAST HDL_POWER GND
J 1
(11675 2700);
DISPLAY 0.872340 (11675 2700);
PAINT GREEN (11675 2700);
DISPLAY INVISIBLE (11675 2700);
FORCEPROP 1 LAST PATH I5
J 0
(11725 2775);
DISPLAY 0.872340 (11725 2775);
PAINT AQUA (11725 2775);
DISPLAY INVISIBLE (11725 2775);
FORCEADD MOSFET_NCH_GDS_ESD_PROTECTED..1
(11625 3125);
FORCEPROP 1 LAST LOCATION U158
J 0
(11767 3089);
DISPLAY 0.723404 (11767 3089);
PAINT GREEN (11767 3089);
FORCEPROP 0 LAST $SEC 1
J 0
(11775 3275);
DISPLAY 0.680851 (11775 3275);
PAINT MONO (11775 3275);
DISPLAY INVISIBLE (11775 3275);
FORCEPROP 0 LAST CDS_SEC 1
J 0
(11775 3275);
DISPLAY 1.021277 (11775 3275);
DISPLAY INVISIBLE (11775 3275);
FORCEPROP 0 LASTPIN (11650 3325) $PN D
R 1
J 0
(11640 3335);
DISPLAY 0.680851 (11640 3335);
PAINT MONO (11640 3335);
FORCEPROP 0 LASTPIN (11450 3125) $PN G
J 2
(11440 3135);
DISPLAY 0.680851 (11440 3135);
PAINT MONO (11440 3135);
FORCEPROP 0 LASTPIN (11650 2925) $PN S
R 1
J 2
(11640 2915);
DISPLAY 0.680851 (11640 2915);
PAINT MONO (11640 2915);
FORCEPROP 2 LAST PART_TYPE SMLF
J 0
(11775 3225);
DISPLAY 0.680851 (11775 3225);
FORCEPROP 1 LAST MATERIAL IC
J 0
(11767 2980);
DISPLAY 0.723404 (11767 2980);
PAINT GREEN (11767 2980);
FORCEPROP 2 LAST VALUE 2N7002K
J 0
(11775 3175);
DISPLAY 0.680851 (11775 3175);
FORCEPROP 2 LAST CDS_LIB pure_quanta
J 0
(11625 3125);
DISPLAY INVISIBLE (11625 3125);
FORCEPROP 1 LAST CDS_LMAN_SYM_OUTLINE -125,150,125,-150
J 0
(11625 3125);
DISPLAY 0.468085 (11625 3125);
PAINT GREEN (11625 3125);
DISPLAY INVISIBLE (11625 3125);
FORCEPROP 1 LAST NEEDS_NO_SIZE TRUE
J 0
(11750 3015);
DISPLAY 0.723404 (11750 3015);
PAINT GREEN (11750 3015);
DISPLAY INVISIBLE (11750 3015);
FORCEPROP 1 LAST PATH I6
J 0
(11750 2975);
DISPLAY 0.723404 (11750 2975);
PAINT GREEN (11750 2975);
DISPLAY INVISIBLE (11750 2975);
FORCEPROP 1 LAST PART_NUMBER BAM70020002
J 0
(11767 3037);
DISPLAY 0.723404 (11767 3037);
PAINT GREEN (11767 3037);
DISPLAY INVISIBLE (11767 3037);
FORCEADD Q_RES..1
(12575 3450);
FORCEPROP 1 LAST LOCATION R2529
J 0
(12325 3450);
DISPLAY 0.787234 (12325 3450);
FORCEPROP 0 LAST $SEC 1
J 0
(12875 3525);
DISPLAY 0.680851 (12875 3525);
PAINT MONO (12875 3525);
DISPLAY INVISIBLE (12875 3525);
FORCEPROP 0 LAST CDS_SEC 1
J 0
(12875 3525);
DISPLAY 1.021277 (12875 3525);
DISPLAY INVISIBLE (12875 3525);
FORCEPROP 1 LASTPIN (12475 3450) $PN 1
J 0
(12487 3462);
DISPLAY 0.787234 (12487 3462);
PAINT MONO (12487 3462);
FORCEPROP 1 LASTPIN (12675 3450) $PN 2
J 0
(12637 3462);
DISPLAY 0.787234 (12637 3462);
PAINT MONO (12637 3462);
FORCEPROP 1 LAST TOLERANCE 5%
J 0
(12750 3450);
DISPLAY 0.404255 (12750 3450);
FORCEPROP 1 LAST VALUE 0
J 2
(12725 3450);
DISPLAY 0.404255 (12725 3450);
FORCEPROP 1 LAST WATTAGE 1/16W
J 2
(12875 3500);
DISPLAY 0.319149 (12875 3500);
FORCEPROP 1 LAST PACK_TYPE 0402LF
J 0
(12700 3500);
DISPLAY 0.319149 (12700 3500);
FORCEPROP 1 LAST MATERIAL CHIP
J 0
(12825 3450);
DISPLAY 0.404255 (12825 3450);
FORCEPROP 2 LAST CDS_LIB pure_quanta
J 0
(12575 3450);
DISPLAY INVISIBLE (12575 3450);
FORCEPROP 1 LAST PATH I7
J 0
(12525 3600);
DISPLAY 0.978723 (12525 3600);
PAINT WHITE (12525 3600);
DISPLAY INVISIBLE (12525 3600);
FORCEPROP 1 LAST PART_NUMBER CS00002JB13
J 0
(12700 3475);
DISPLAY 0.319149 (12700 3475);
DISPLAY INVISIBLE (12700 3475);
FORCEADD Q_RES..2
(11650 3850);
FORCEPROP 1 LAST LOCATION R2528
J 0
(11695 3975);
DISPLAY 0.978723 (11695 3975);
FORCEPROP 0 LAST $SEC 1
J 0
(11700 4025);
DISPLAY 0.680851 (11700 4025);
PAINT MONO (11700 4025);
DISPLAY INVISIBLE (11700 4025);
FORCEPROP 0 LAST CDS_SEC 1
J 0
(11700 4025);
DISPLAY 1.021277 (11700 4025);
DISPLAY INVISIBLE (11700 4025);
FORCEPROP 1 LASTPIN (11650 3950) $PN 1
J 0
(11655 3912);
DISPLAY 0.787234 (11655 3912);
PAINT MONO (11655 3912);
FORCEPROP 1 LASTPIN (11650 3750) $PN 2
J 0
(11655 3760);
DISPLAY 0.787234 (11655 3760);
PAINT MONO (11655 3760);
FORCEPROP 1 LAST PACK_TYPE 0402LF
J 0
(11690 3675);
DISPLAY 0.510638 (11690 3675);
FORCEPROP 1 LAST VALUE 100K
J 0
(11695 3925);
DISPLAY 0.510638 (11695 3925);
FORCEPROP 1 LAST TOLERANCE 1%
J 0
(11695 3875);
DISPLAY 0.510638 (11695 3875);
FORCEPROP 1 LAST MATERIAL CHIP
J 0
(11690 3775);
DISPLAY 0.510638 (11690 3775);
FORCEPROP 1 LAST WATTAGE 1/16W
J 0
(11690 3825);
DISPLAY 0.510638 (11690 3825);
FORCEPROP 2 LAST CDS_LIB pure_quanta
J 0
(11650 3850);
DISPLAY INVISIBLE (11650 3850);
FORCEPROP 1 LAST PATH I8
J 0
(11700 4025);
DISPLAY 0.978723 (11700 4025);
PAINT WHITE (11700 4025);
DISPLAY INVISIBLE (11700 4025);
FORCEPROP 1 LAST PART_NUMBER CS41002FB09
J 0
(11690 3725);
DISPLAY 0.510638 (11690 3725);
DISPLAY INVISIBLE (11690 3725);
FORCEADD UNIVERSAL_POWER..1
(11650 4100);
FORCEPROP 3 LASTPIN (11650 4050) SIG_NAME P12V_AUX\g
J 0
(11660 4060);
DISPLAY 0.659574 (11660 4060);
PAINT MONO (11660 4060);
DISPLAY INVISIBLE (11660 4060);
FORCEPROP 1 LAST HDL_POWER P12V_AUX
J 1
(11650 4150);
DISPLAY 0.872340 (11650 4150);
PAINT GREEN (11650 4150);
FORCEPROP 2 LAST CDS_LIB pure_quanta_power
J 0
(11650 4100);
DISPLAY INVISIBLE (11650 4100);
FORCEPROP 1 LAST PATH I9
J 0
(11700 4125);
DISPLAY 0.872340 (11700 4125);
PAINT AQUA (11700 4125);
DISPLAY INVISIBLE (11700 4125);
FORCEADD DNS..2
(9450 1900);
PAINT RED (9450 1900);
FORCEPROP 2 LAST CDS_LIB mstr_misc
J 0
(9450 1900);
DISPLAY INVISIBLE (9450 1900);
FORCEPROP 1 LAST COMMENT_BODY TRUE
J 0
(9450 1900);
DISPLAY INVISIBLE (9450 1900);
FORCEADD DNS..2
(11525 1475);
PAINT RED (11525 1475);
FORCEPROP 2 LAST CDS_LIB mstr_misc
J 0
(11525 1475);
DISPLAY INVISIBLE (11525 1475);
FORCEPROP 1 LAST COMMENT_BODY TRUE
J 0
(11525 1475);
DISPLAY INVISIBLE (11525 1475);
FORCEADD DNS..2
(13925 1400);
PAINT RED (13925 1400);
FORCEPROP 2 LAST CDS_LIB mstr_misc
J 0
(13925 1400);
DISPLAY INVISIBLE (13925 1400);
FORCEPROP 1 LAST COMMENT_BODY TRUE
J 0
(13925 1400);
DISPLAY INVISIBLE (13925 1400);
FORCEADD DNS..2
(12450 2050);
PAINT RED (12450 2050);
FORCEPROP 2 LAST CDS_LIB mstr_misc
J 0
(12450 2050);
DISPLAY INVISIBLE (12450 2050);
FORCEPROP 1 LAST COMMENT_BODY TRUE
J 0
(12450 2050);
DISPLAY INVISIBLE (12450 2050);
FORCEADD QUANTA_TITLE_BLOCK_C..1
(16850 -1225);
FORCEPROP 0 LAST CDS_CON_LAST_MODIFIED Thu Sep 14 16:12:32 2023
J 0
(14965 -1210);
PAINT MONO (14965 -1210);
DISPLAY INVISIBLE (14965 -1210);
FORCEPROP 1 LAST CUSTOM_TXT_CDS <CON_LAST_MODIFIED>
J 0
(14965 -1210);
DISPLAY 0.978723 (14965 -1210);
FORCEPROP 2 LAST CUSTOM_TXT_CDS <XR_PAGE_TITLE>
J 0
(8960 4025);
DISPLAY 0.638298 (8960 4025);
PAINT PINK (8960 4025);
DISPLAY INVISIBLE (8960 4025);
FORCEPROP 1 LAST CUSTOM_TXT_CDS <NAME_2>
J 0
(13675 -1175);
FORCEPROP 1 LAST CUSTOM_TXT_CDS <NAME_1>
J 0
(13675 -1050);
FORCEPROP 1 LAST CUSTOM_TXT_CDS <Q_NUMBER>
J 0
(15447 -1122);
DISPLAY 1.212766 (15447 -1122);
FORCEPROP 1 LAST CUSTOM_TXT_CDS <Q_PROJ>
J 0
(14468 -1123);
DISPLAY 1.212766 (14468 -1123);
FORCEPROP 1 LAST CUSTOM_TXT_CDS <Q_REV>
J 0
(16666 -1122);
DISPLAY 1.212766 (16666 -1122);
FORCEPROP 1 LAST CUSTOM_TXT_CDS <CON_PAGE_NUM> OF <CON_TOTAL_PAGES>
J 0
(16404 -1207);
DISPLAY 0.978723 (16404 -1207);
FORCEPROP 1 LAST Q_TITLE PSU POWER CONNECTORS
J 0
(7584 -1199);
DISPLAY 2.446809 (7584 -1199);
PAINT GREEN (7584 -1199);
FORCEPROP 2 LAST CDS_XR_PAGE_TITLE CR-243 : @T6G_MB_LIB.T6G(SCH_1):PAGE243
J 0
(8960 4025);
DISPLAY 0.638298 (8960 4025);
PAINT PINK (8960 4025);
DISPLAY INVISIBLE (8960 4025);
FORCEPROP 2 LAST CDS_LIB pure_quanta
J 0
(16850 -1225);
PAINT MONO (16850 -1225);
DISPLAY INVISIBLE (16850 -1225);
FORCEPROP 1 LAST CDS_LMAN_SYM_OUTLINE -9475,6775,100,-125
J 0
(16850 -1225);
DISPLAY 0.468085 (16850 -1225);
PAINT GREEN (16850 -1225);
DISPLAY INVISIBLE (16850 -1225);
FORCEPROP 2 LAST PAGE_BORDER TRUE
J 0
(8960 4025);
DISPLAY 0.638298 (8960 4025);
PAINT PINK (8960 4025);
DISPLAY INVISIBLE (8960 4025);
FORCEPROP 1 LAST Q_DEPT BU9
J 1
(13087 -1176);
DISPLAY 1.957447 (13087 -1176);
PAINT GREEN (13087 -1176);
DISPLAY INVISIBLE (13087 -1176);
FORCEPROP 1 LAST COMMENT_BODY TRUE
J 0
(16862 -1238);
DISPLAY 0.978723 (16862 -1238);
PAINT GREEN (16862 -1238);
DISPLAY INVISIBLE (16862 -1238);
FORCEADD DNS..2
(9525 850);
PAINT RED (9525 850);
FORCEPROP 2 LAST CDS_LIB mstr_misc
J 0
(9525 850);
DISPLAY INVISIBLE (9525 850);
FORCEPROP 1 LAST COMMENT_BODY TRUE
J 0
(9525 850);
DISPLAY INVISIBLE (9525 850);
FORCEADD DNS..2
(10025 1325);
PAINT RED (10025 1325);
FORCEPROP 2 LAST CDS_LIB mstr_misc
J 0
(10025 1325);
DISPLAY INVISIBLE (10025 1325);
FORCEPROP 1 LAST COMMENT_BODY TRUE
J 0
(10025 1325);
DISPLAY INVISIBLE (10025 1325);
WIRE 16 -1 (14600 4250)(14600 4150);
WIRE 16 -1 (14025 3250)(14025 3100);
WIRE 16 -1 (12400 1950)(12400 1800);
WIRE 16 -1 (9450 800)(9450 500);
WIRE 16 -1 (9375 2000)(9375 2250);
WIRE 16 -1 (14500 2150)(14500 2350);
WIRE 16 -1 (11650 2825)(11650 2925);
WIRE 16 -1 (11650 4050)(11650 3950);
WIRE 16 -1 (14600 3800)(14600 3950);
WIRE 16 -1 (14600 3800)(14025 3800);
FORCEPROP 2 LAST SIG_NAME P12V_AUX_BLEEDING
J 0
(14115 3810);
DISPLAY 0.553191 (14115 3810);
PAINT WHITE (14115 3810);
FORCEPROP 2 LASTPROP $XRERR UNIQUE?
J 0
(13875 3810);
DISPLAY 0.638298 (13875 3810);
PAINT MONO (13875 3810);
DISPLAY INVISIBLE (13875 3810);
WIRE 16 -1 (14025 3800)(14025 3650);
WIRE 16 -1 (12675 3450)(13825 3450);
FORCEPROP 2 LAST SIG_NAME FM_P12V_HSC_EN_R_N
J 0
(13065 3460);
DISPLAY 0.638298 (13065 3460);
PAINT WHITE (13065 3460);
FORCEPROP 2 LASTPROP $XRERR UNIQUE?
J 0
(12825 3460);
DISPLAY 0.638298 (12825 3460);
PAINT MONO (12825 3460);
DISPLAY INVISIBLE (12825 3460);
WIRE 16 -1 (11650 3750)(11650 3450);
WIRE 16 -1 (12475 3450)(11650 3450);
FORCEPROP 2 LAST SIG_NAME FM_P12V_HSC_EN_N
J 0
(11715 3460);
DISPLAY 0.638298 (11715 3460);
PAINT WHITE (11715 3460);
FORCEPROP 2 LASTPROP $XRERR UNIQUE?
J 0
(11475 3460);
DISPLAY 0.638298 (11475 3460);
PAINT MONO (11475 3460);
DISPLAY INVISIBLE (11475 3460);
WIRE 16 -1 (11650 3325)(11650 3450);
WIRE 16 -1 (9100 3125)(10225 3125);
FORCEPROP 2 LAST SIG_NAME MB0_P12V_STBY_PWRGD
J 0
(9265 3135);
DISPLAY 0.638298 (9265 3135);
PAINT WHITE (9265 3135);
WIRE 16 -1 (10425 3125)(11450 3125);
FORCEPROP 2 LAST SIG_NAME FM_P12V_HSC_EN_R
J 0
(10790 3135);
DISPLAY 0.638298 (10790 3135);
PAINT WHITE (10790 3135);
FORCEPROP 2 LASTPROP $XRERR UNIQUE?
J 0
(10550 3135);
DISPLAY 0.638298 (10550 3135);
PAINT MONO (10550 3135);
DISPLAY INVISIBLE (10550 3135);
WIRE 16 -1 (11225 1400)(10075 1400);
FORCEPROP 2 LAST SIG_NAME FM_AC_PWR_BTN_PLD_N
J 0
(10315 1410);
DISPLAY 0.680851 (10315 1410);
FORCEPROP 2 LASTPROP $XRERR UNIQUE?
J 0
(10075 1410);
DISPLAY 0.638298 (10075 1410);
PAINT MONO (10075 1410);
DISPLAY INVISIBLE (10075 1410);
WIRE 16 -1 (8425 1400)(9375 1400);
FORCEPROP 2 LAST SIG_NAME FM_AC_PWR_BTN_R_N
J 0
(8515 1410);
DISPLAY 0.680851 (8515 1410);
WIRE 16 -1 (9375 1800)(9375 1400);
WIRE 16 -1 (9450 1400)(9375 1400);
WIRE 16 -1 (9875 1400)(9450 1400);
WIRE 16 -1 (9450 1400)(9450 1000);
WIRE 16 -1 (11875 1400)(13775 1400);
FORCEPROP 2 LAST SIG_NAME FM_AC_PWR_BTN_PLD_ISO_R_N
J 0
(12465 1410);
DISPLAY 0.680851 (12465 1410);
FORCEPROP 2 LASTPROP $XRERR UNIQUE?
J 0
(12225 1410);
DISPLAY 0.638298 (12225 1410);
PAINT MONO (12225 1410);
DISPLAY INVISIBLE (12225 1410);
WIRE 16 -1 (11875 1300)(12600 1300);
FORCEPROP 2 LAST SIG_NAME NC_U8004_2Y
J 0
(12065 1310);
DISPLAY 0.553191 (12065 1310);
FORCEPROP 2 LASTPROP $XRERR UNIQUE?
J 0
(12630 1300);
DISPLAY 0.638298 (12630 1300);
PAINT MONO (12630 1300);
DISPLAY INVISIBLE (12630 1300);
WIRE 16 -1 (12200 2300)(12400 2300);
WIRE 16 -1 (12200 2325)(12200 2300);
WIRE 16 -1 (12200 2300)(12200 1350);
WIRE 16 -1 (12400 2300)(12400 2150);
WIRE 16 -1 (12200 1350)(11875 1350);
WIRE 16 -1 (11225 1350)(11150 1350);
WIRE 16 -1 (11150 1350)(11150 1300);
WIRE 16 -1 (11150 1300)(11225 1300);
WIRE 16 -1 (11150 1300)(11150 1250);
WIRE 16 -1 (13975 1400)(14500 1400);
WIRE 16 -1 (14500 1400)(16000 1400);
FORCEPROP 2 LAST SIG_NAME FM_AC_PWR_BTN_PLD_ISO_N
J 0
(14815 1410);
DISPLAY 0.680851 (14815 1410);
WIRE 16 -1 (14500 1950)(14500 1400);
DOT 1 (11150 1300);
DOT 1 (11650 3450);
DOT 1 (9375 1400);
DOT 1 (12200 2300);
DOT 1 (9450 1400);
DOT 1 (14500 1400);
QUIT
